# S9S_MB_2U (Grand Teton) — schematic netlist excerpt (pin names and nets, part order shuffled) for the footprints in the layout excerpt that follows; sources: Cadence DE-HDL packaged netlist, KiCad conversion of 03242023_DA0F0TMBIJ0_F0T_Motherboard_J_brd_V01_OCP.brd

C2388  Q_CAP  100NF 50V 10% EMPTY  pkg C0402  page 306 : A = OC_P2V5_COMP ; B = GND
R3169  Q_RES  0 5% CHIP  pkg 0402LF  page 159 : A = OCP_V3_2_ISO_BIF0_EN ; B = OCP_V3_2_BIF0_R_N

(kicad_pcb
	(version 20260206)
	(generator "pcbnew")
	(generator_version "10.0")
	(general
		(thickness 1.6)
		(legacy_teardrops no)
	)
	(paper "A4")
	(title_block
		(title "03242023_DA0F0TMBIJ0_F0T_Motherboard_J_brd_V01_OCP.brd")
		(comment 1 "Grand Teton / footprints 70-71 of 6105")
	)
	(layers
		(0 "F.Cu" signal "TOP")
		(4 "In1.Cu" signal "GND")
		(6 "In2.Cu" signal "IN1")
		(8 "In3.Cu" signal "GND1")
		(10 "In4.Cu" signal "IN2")
		(12 "In5.Cu" signal "GND2")
		(14 "In6.Cu" signal "IN3")
		(16 "In7.Cu" signal "GND3")
		(18 "In8.Cu" signal "VCC")
		(20 "In9.Cu" signal "VCC1")
		(22 "In10.Cu" signal "GND4")
		(24 "In11.Cu" signal "IN4")
		(26 "In12.Cu" signal "GND5")
		(28 "In13.Cu" signal "IN5")
		(30 "In14.Cu" signal "GND6")
		(32 "In15.Cu" signal "IN6")
		(34 "In16.Cu" signal "GND7")
		(2 "B.Cu" signal "BOTTOM")
		(9 "F.Adhes" user "F.Adhesive")
		(11 "B.Adhes" user "B.Adhesive")
		(13 "F.Paste" user "Package Geometry/Pastemask Top")
		(15 "B.Paste" user "Package Geometry/Pastemask Bottom")
		(5 "F.SilkS" user "Ref Des/Silkscreen Top")
		(7 "B.SilkS" user "Ref Des/Silkscreen Bottom")
		(1 "F.Mask" user "Board Geometry/Soldermask Top")
		(3 "B.Mask" user "Board Geometry/Soldermask Bottom")
		(17 "Dwgs.User" user "User.Drawings")
		(19 "Cmts.User" user "User.Comments")
		(21 "Eco1.User" user "User.Eco1")
		(23 "Eco2.User" user "User.Eco2")
		(25 "Edge.Cuts" user "Board Geometry/Outline")
		(27 "Margin" user)
		(31 "F.CrtYd" user "Package Geometry/Place Bound Top")
		(29 "B.CrtYd" user "Package Geometry/Place Bound Bottom")
		(35 "F.Fab" user "Ref Des/Assembly Top")
		(33 "B.Fab" user "Ref Des/Assembly Bottom")
	)
	(footprint ""
		(layer "F.Cu")
		(at 63.30188 -16.220948 -90)
		(property "Reference" "R3169"
			(at 0 0 270)
			(layer "F.SilkS")
			(hide yes)
			(effects
				(font
					(size 1.27 1.27)
				)
			)
		)
		(property "Value" ""
			(at 0 0 270)
			(layer "F.Fab")
			(effects
				(font
					(size 1.27 1.27)
				)
			)
		)
		(duplicate_pad_numbers_are_jumpers no)
		(fp_line
			(start -0.7874 0.4064)
			(end -0.7874 -0.4064)
			(stroke
				(width 0.1524)
				(type default)
			)
			(layer "F.SilkS")
		)
		(fp_line
			(start 0.7874 0.4064)
			(end -0.7874 0.4064)
			(stroke
				(width 0.1524)
				(type default)
			)
			(layer "F.SilkS")
		)
		(fp_line
			(start -0.7874 -0.4064)
			(end 0.7874 -0.4064)
			(stroke
				(width 0.1524)
				(type default)
			)
			(layer "F.SilkS")
		)
		(fp_line
			(start 0.7874 -0.4064)
			(end 0.7874 0.4064)
			(stroke
				(width 0.1524)
				(type default)
			)
			(layer "F.SilkS")
		)
		(fp_line
			(start -0.67945 0.3048)
			(end -0.67945 -0.305054)
			(stroke
				(width 0.1)
				(type default)
			)
			(layer "F.Fab")
		)
		(fp_line
			(start -0.12065 0.3048)
			(end -0.67945 0.3048)
			(stroke
				(width 0.1)
				(type default)
			)
			(layer "F.Fab")
		)
		(fp_line
			(start 0.120396 0.3048)
			(end 0.120396 0.2794)
			(stroke
				(width 0.1)
				(type default)
			)
			(layer "F.Fab")
		)
		(fp_line
			(start 0.67945 0.3048)
			(end 0.120396 0.3048)
			(stroke
				(width 0.1)
				(type default)
			)
			(layer "F.Fab")
		)
		(fp_line
			(start -0.12065 0.2794)
			(end -0.12065 0.3048)
			(stroke
				(width 0.1)
				(type default)
			)
			(layer "F.Fab")
		)
		(fp_line
			(start 0.120396 0.2794)
			(end -0.12065 0.2794)
			(stroke
				(width 0.1)
				(type default)
			)
			(layer "F.Fab")
		)
		(fp_line
			(start -0.12065 -0.2794)
			(end 0.12065 -0.2794)
			(stroke
				(width 0.1)
				(type default)
			)
			(layer "F.Fab")
		)
		(fp_line
			(start 0.12065 -0.2794)
			(end 0.12065 -0.3048)
			(stroke
				(width 0.1)
				(type default)
			)
			(layer "F.Fab")
		)
		(fp_line
			(start 0.12065 -0.3048)
			(end 0.67945 -0.3048)
			(stroke
				(width 0.1)
				(type default)
			)
			(layer "F.Fab")
		)
		(fp_line
			(start 0.67945 -0.3048)
			(end 0.67945 0.3048)
			(stroke
				(width 0.1)
				(type default)
			)
			(layer "F.Fab")
		)
		(fp_line
			(start -0.67945 -0.305054)
			(end -0.12065 -0.305054)
			(stroke
				(width 0.1)
				(type default)
			)
			(layer "F.Fab")
		)
		(fp_line
			(start -0.12065 -0.305054)
			(end -0.12065 -0.2794)
			(stroke
				(width 0.1)
				(type default)
			)
			(layer "F.Fab")
		)
		(pad "1" smd circle
			(at -0.40005 0 270)
			(size 0 0)
			(layers "F.Cu" "F.Mask" "F.Paste")
			(net "OCP_V3_2_ISO_BIF0_EN")
		)
		(pad "2" smd circle
			(at 0.40005 0 270)
			(size 0 0)
			(layers "F.Cu" "F.Mask" "F.Paste")
			(net "OCP_V3_2_BIF0_R_N")
		)
	)
	(footprint ""
		(layer "F.Cu")
		(at 181.80812 -411.20822 -90)
		(property "Reference" "C2388"
			(at 0 0 270)
			(layer "F.SilkS")
			(hide yes)
			(effects
				(font
					(size 1.27 1.27)
				)
			)
		)
		(property "Value" ""
			(at 0 0 270)
			(layer "F.Fab")
			(effects
				(font
					(size 1.27 1.27)
				)
			)
		)
		(duplicate_pad_numbers_are_jumpers no)
		(fp_line
			(start -0.7874 0.4064)
			(end -0.7874 -0.4064)
			(stroke
				(width 0.1524)
				(type default)
			)
			(layer "F.SilkS")
		)
		(fp_line
			(start 0.7874 0.4064)
			(end -0.7874 0.4064)
			(stroke
				(width 0.1524)
				(type default)
			)
			(layer "F.SilkS")
		)
		(fp_line
			(start -0.7874 -0.4064)
			(end 0.7874 -0.4064)
			(stroke
				(width 0.1524)
				(type default)
			)
			(layer "F.SilkS")
		)
		(fp_line
			(start 0.7874 -0.4064)
			(end 0.7874 0.4064)
			(stroke
				(width 0.1524)
				(type default)
			)
			(layer "F.SilkS")
		)
		(fp_line
			(start -0.67945 0.3048)
			(end -0.67945 -0.305054)
			(stroke
				(width 0.1)
				(type default)
			)
			(layer "F.Fab")
		)
		(fp_line
			(start -0.12065 0.3048)
			(end -0.67945 0.3048)
			(stroke
				(width 0.1)
				(type default)
			)
			(layer "F.Fab")
		)
		(fp_line
			(start 0.120396 0.3048)
			(end 0.120396 0.2794)
			(stroke
				(width 0.1)
				(type default)
			)
			(layer "F.Fab")
		)
		(fp_line
			(start 0.67945 0.3048)
			(end 0.120396 0.3048)
			(stroke
				(width 0.1)
				(type default)
			)
			(layer "F.Fab")
		)
		(fp_line
			(start -0.12065 0.2794)
			(end -0.12065 0.3048)
			(stroke
				(width 0.1)
				(type default)
			)
			(layer "F.Fab")
		)
		(fp_line
			(start 0.120396 0.2794)
			(end -0.12065 0.2794)
			(stroke
				(width 0.1)
				(type default)
			)
			(layer "F.Fab")
		)
		(fp_line
			(start -0.12065 -0.2794)
			(end 0.12065 -0.2794)
			(stroke
				(width 0.1)
				(type default)
			)
			(layer "F.Fab")
		)
		(fp_line
			(start 0.12065 -0.2794)
			(end 0.12065 -0.3048)
			(stroke
				(width 0.1)
				(type default)
			)
			(layer "F.Fab")
		)
		(fp_line
			(start 0.12065 -0.3048)
			(end 0.67945 -0.3048)
			(stroke
				(width 0.1)
				(type default)
			)
			(layer "F.Fab")
		)
		(fp_line
			(start 0.67945 -0.3048)
			(end 0.67945 0.3048)
			(stroke
				(width 0.1)
				(type default)
			)
			(layer "F.Fab")
		)
		(fp_line
			(start -0.67945 -0.305054)
			(end -0.12065 -0.305054)
			(stroke
				(width 0.1)
				(type default)
			)
			(layer "F.Fab")
		)
		(fp_line
			(start -0.12065 -0.305054)
			(end -0.12065 -0.2794)
			(stroke
				(width 0.1)
				(type default)
			)
			(layer "F.Fab")
		)
		(pad "1" smd circle
			(at -0.40005 0 270)
			(size 0 0)
			(layers "F.Cu" "F.Mask" "F.Paste")
			(net "OC_P2V5_COMP")
		)
		(pad "2" smd circle
			(at 0.40005 0 270)
			(size 0 0)
			(layers "F.Cu" "F.Mask" "F.Paste")
			(net "GND")
		)
	)
)
